#ISCELL
  pure_quanta quanta_title_block_c *
  *
#CELL
  pure_quanta q_cap *
  page75_i1
#ISCELL
  logical_power universal_power *
  page75_i10
#CELL
  pure_quanta q_cap *
  page75_i11
#ISCELL
  logical_power universal_power *
  page75_i12
#CELL
  pure_quanta q_cap *
  page75_i13
#CELL
  pure_quanta q_cap *
  page75_i14
#ISCELL
  logical_power universal_gnd *
  page75_i15
#CELL
  pure_quanta q_cap *
  page75_i16
#CELL
  pure_quanta q_cap *
  page75_i17
#CELL
  pure_quanta q_cap *
  page75_i18
#CELL
  pure_quanta q_cap *
  page75_i19
#ISCELL
  logical_power universal_power *
  page75_i2
#ISCELL
  logical_power universal_power *
  page75_i20
#CELL
  pure_quanta q_cap *
  page75_i21
#ISCELL
  logical_power universal_power *
  page75_i22
#CELL
  pure_quanta q_cap *
  page75_i23
#ISCELL
  logical_power universal_power *
  page75_i24
#CELL
  pure_quanta q_cap *
  page75_i25
#CELL
  pure_quanta q_cap *
  page75_i26
#CELL
  pure_quanta q_cap *
  page75_i27
#CELL
  pure_quanta q_cap *
  page75_i28
#CELL
  pure_quanta q_cap *
  page75_i29
#CELL
  pure_quanta q_cap *
  page75_i3
#ISCELL
  logical_power universal_gnd *
  page75_i30
#CELL
  pure_quanta q_cap *
  page75_i31
#CELL
  pure_quanta q_cap *
  page75_i32
#CELL
  pure_quanta q_cap *
  page75_i33
#CELL
  pure_quanta q_cap *
  page75_i34
#CELL
  pure_quanta q_cap *
  page75_i35
#CELL
  pure_quanta q_cap *
  page75_i36
#CELL
  pure_quanta q_cap *
  page75_i37
#CELL
  pure_quanta q_cap *
  page75_i38
#CELL
  pure_quanta q_cap *
  page75_i39
#CELL
  pure_quanta q_cap *
  page75_i4
#CELL
  pure_quanta q_cap *
  page75_i40
#CELL
  pure_quanta q_cap *
  page75_i41
#ISCELL
  logical_power universal_power *
  page75_i42
#CELL
  pure_quanta q_cap *
  page75_i43
#CELL
  pure_quanta q_cap *
  page75_i44
#ISCELL
  logical_power universal_power *
  page75_i45
#CELL
  pure_quanta q_cap *
  page75_i46
#CELL
  pure_quanta q_cap *
  page75_i47
#CELL
  pure_quanta q_cap *
  page75_i48
#CELL
  pure_quanta q_cap *
  page75_i49
#ISCELL
  logical_power universal_gnd *
  page75_i5
#CELL
  pure_quanta q_cap *
  page75_i50
#CELL
  pure_quanta q_cap *
  page75_i51
#CELL
  pure_quanta q_cap *
  page75_i52
#ISCELL
  logical_power universal_gnd *
  page75_i53
#CELL
  pure_quanta q_cap *
  page75_i54
#CELL
  pure_quanta q_cap *
  page75_i55
#CELL
  pure_quanta q_cap *
  page75_i56
#ISCELL
  logical_power universal_gnd *
  page75_i57
#CELL
  pure_quanta q_cap *
  page75_i58
#CELL
  pure_quanta q_cap *
  page75_i59
#CELL
  pure_quanta q_cap *
  page75_i6
#ISCELL
  logical_power universal_gnd *
  page75_i60
#CELL
  pure_quanta q_cap *
  page75_i61
#CELL
  pure_quanta q_cap *
  page75_i62
#ISCELL
  logical_power universal_gnd *
  page75_i63
#CELL
  pure_quanta q_cap *
  page75_i64
#ISCELL
  logical_power universal_power *
  page75_i65
#ISCELL
  logical_power universal_gnd *
  page75_i66
#CELL
  pure_quanta q_cap *
  page75_i67
#CELL
  pure_quanta q_cap *
  page75_i68
#ISCELL
  logical_power universal_gnd *
  page75_i7
#CELL
  pure_quanta q_cap *
  page75_i8
#CELL
  pure_quanta q_cap *
  page75_i9
